(kicad_pcb
	(version 20260206)
	(generator "pcbnew")
	(generator_version "10.0")
	(general
		(thickness 1.6)
		(legacy_teardrops no)
	)
	(paper "A4")
	(title_block
		(title "dpb — 14545-sa.0730WZS0815.brd")
		(comment 1 "Honey Badger (Wiwynn) / footprints 916-917 of 1066")
	)
	(layers
		(0 "F.Cu" signal "TOP")
		(4 "In1.Cu" signal "L2GND")
		(6 "In2.Cu" signal "L3")
		(8 "In3.Cu" signal "L4VCC")
		(10 "In4.Cu" signal "L5VCC")
		(12 "In5.Cu" signal "L6")
		(14 "In6.Cu" signal "L7GND")
		(2 "B.Cu" signal "BOTTOM")
		(9 "F.Adhes" user "F.Adhesive")
		(11 "B.Adhes" user "B.Adhesive")
		(13 "F.Paste" user "Package Geometry/Pastemask Top")
		(15 "B.Paste" user "Package Geometry/Pastemask Bottom")
		(5 "F.SilkS" user "Ref Des/Silkscreen Top")
		(7 "B.SilkS" user "Ref Des/Silkscreen Bottom")
		(1 "F.Mask" user "Board Geometry/Soldermask Top")
		(3 "B.Mask" user "Board Geometry/Soldermask Bottom")
		(17 "Dwgs.User" user "User.Drawings")
		(19 "Cmts.User" user "User.Comments")
		(21 "Eco1.User" user "User.Eco1")
		(23 "Eco2.User" user "User.Eco2")
		(25 "Edge.Cuts" user "Board Geometry/Outline")
		(27 "Margin" user)
		(31 "F.CrtYd" user "Package Geometry/Place Bound Top")
		(29 "B.CrtYd" user "Package Geometry/Place Bound Bottom")
		(35 "F.Fab" user "Ref Des/Assembly Top")
		(33 "B.Fab" user "Ref Des/Assembly Bottom")
	)
	(footprint ""
		(layer "F.Cu")
		(at 2.500122 -55.204614 -90)
		(property "Reference" "CN9"
			(at 0 0 270)
			(layer "F.SilkS")
			(hide yes)
			(effects
				(font
					(size 1.27 1.27)
				)
			)
		)
		(property "Value" "PCISLT36-27-GP"
			(at 5.281422 -7.491476 270)
			(unlocked yes)
			(layer "F.Fab")
			(hide yes)
			(effects
				(font
					(size 1.016 1.016)
					(thickness 0.1524)
				)
			)
		)
		(property "Device Type" "G630H3612248EU"
			(at 5.281422 -9.015476 270)
			(unlocked yes)
			(layer "F.Fab")
			(hide yes)
			(effects
				(font
					(size 1.016 1.016)
					(thickness 0.1524)
				)
			)
		)
		(duplicate_pad_numbers_are_jumpers no)
		(fp_line
			(start -14.899894 2.499868)
			(end -1.450086 2.499868)
			(stroke
				(width 0.1524)
				(type default)
			)
			(layer "F.SilkS")
		)
		(fp_line
			(start -1.450086 2.499868)
			(end -0.94996 1.999742)
			(stroke
				(width 0.1524)
				(type default)
			)
			(layer "F.SilkS")
		)
		(fp_line
			(start 1.450086 2.499868)
			(end 18.899886 2.499868)
			(stroke
				(width 0.1524)
				(type default)
			)
			(layer "F.SilkS")
		)
		(fp_line
			(start 18.899886 2.499868)
			(end 19.400012 1.999742)
			(stroke
				(width 0.1524)
				(type default)
			)
			(layer "F.SilkS")
		)
		(fp_line
			(start -15.40002 1.999742)
			(end -14.899894 2.499868)
			(stroke
				(width 0.1524)
				(type default)
			)
			(layer "F.SilkS")
		)
		(fp_line
			(start -0.94996 1.999742)
			(end -0.94996 -2.55016)
			(stroke
				(width 0.1524)
				(type default)
			)
			(layer "F.SilkS")
		)
		(fp_line
			(start 0.94996 1.999742)
			(end 1.450086 2.499868)
			(stroke
				(width 0.1524)
				(type default)
			)
			(layer "F.SilkS")
		)
		(fp_line
			(start 19.400012 1.999742)
			(end 19.400012 -4.064)
			(stroke
				(width 0.1524)
				(type default)
			)
			(layer "F.SilkS")
		)
		(fp_line
			(start 0.94996 -2.539746)
			(end 0.94996 1.999742)
			(stroke
				(width 0.1524)
				(type default)
			)
			(layer "F.SilkS")
		)
		(fp_line
			(start 0.94996 -2.55016)
			(end 0.94996 -2.539746)
			(stroke
				(width 0.1524)
				(type default)
			)
			(layer "F.SilkS")
		)
		(fp_line
			(start -15.40002 -4.064)
			(end -15.40002 1.999742)
			(stroke
				(width 0.1524)
				(type default)
			)
			(layer "F.SilkS")
		)
		(fp_line
			(start 19.400012 -4.064)
			(end -15.40002 -4.064)
			(stroke
				(width 0.1524)
				(type default)
			)
			(layer "F.SilkS")
		)
		(fp_line
			(start 11.6713 -4.1529)
			(end 11.2903 -4.1529)
			(stroke
				(width 0.3302)
				(type default)
			)
			(layer "F.SilkS")
		)
		(fp_arc
			(start -0.94996 -2.55016)
			(mid 0 -3.50012)
			(end 0.94996 -2.55016)
			(stroke
				(width 0.1524)
				(type default)
			)
			(layer "F.SilkS")
		)
		(fp_poly
			(pts
				(xy 11.474704 -4.1402) (xy 10.966704 -4.6482) (xy 11.982704 -4.6482)
			)
			(stroke
				(width 0)
				(type default)
			)
			(fill yes)
			(layer "F.SilkS")
		)
		(fp_poly
			(pts
				(xy -10.4902 14.986) (xy -10.4902 4.8006) (xy -15.3924 4.8006) (xy -15.3924 -3.81) (xy 19.4056 -3.81)
				(xy 19.4056 4.8006) (xy 14.5034 4.8006) (xy 14.5034 14.986)
			)
			(stroke
				(width 0)
				(type default)
			)
			(fill no)
			(layer "B.CrtYd")
		)
		(fp_poly
			(pts
				(xy -10.9982 15.494) (xy -10.9982 5.3086) (xy -15.9004 5.3086) (xy -15.9004 -4.318) (xy 19.9136 -4.318)
				(xy 19.9136 5.3086) (xy 15.0114 5.3086) (xy 15.0114 15.494) (xy 0.00254 15.494) (xy 0.00254 14.986)
				(xy 14.5034 14.986) (xy 14.5034 4.8006) (xy 19.4056 4.8006) (xy 19.4056 -3.81) (xy -15.3924 -3.81)
				(xy -15.3924 4.8006) (xy -10.4902 4.8006) (xy -10.4902 14.986) (xy -0.00254 14.986) (xy -0.00254 15.494)
			)
			(stroke
				(width 0)
				(type default)
			)
			(fill no)
			(layer "B.CrtYd")
		)
		(fp_poly
			(pts
				(xy -10.4902 14.986) (xy -10.4902 4.8006) (xy -15.3924 4.8006) (xy -15.3924 -3.81) (xy 19.4056 -3.81)
				(xy 19.4056 4.8006) (xy 14.5034 4.8006) (xy 14.5034 14.986)
			)
			(stroke
				(width 0)
				(type default)
			)
			(fill no)
			(layer "F.CrtYd")
		)
		(fp_poly
			(pts
				(xy -10.9982 15.494) (xy -10.9982 5.3086) (xy -15.9004 5.3086) (xy -15.9004 -4.318) (xy 19.9136 -4.318)
				(xy 19.9136 5.3086) (xy 15.0114 5.3086) (xy 15.0114 15.494) (xy 0.00254 15.494) (xy 0.00254 14.986)
				(xy 14.5034 14.986) (xy 14.5034 4.8006) (xy 19.4056 4.8006) (xy 19.4056 -3.81) (xy -15.3924 -3.81)
				(xy -15.3924 4.8006) (xy -10.4902 4.8006) (xy -10.4902 14.986) (xy -0.00254 14.986) (xy -0.00254 15.494)
			)
			(stroke
				(width 0)
				(type default)
			)
			(fill no)
			(layer "F.CrtYd")
		)
		(fp_poly
			(pts
				(xy -10.9982 15.494) (xy -10.9982 5.3086) (xy -15.9004 5.3086) (xy -15.9004 -4.318) (xy 19.9136 -4.318)
				(xy 19.9136 5.3086) (xy 15.0114 5.3086) (xy 15.0114 15.494)
			)
			(stroke
				(width 0)
				(type default)
			)
			(fill no)
			(layer "B.Fab")
		)
		(fp_poly
			(pts
				(xy -10.9982 15.494) (xy -10.9982 5.3086) (xy -15.9004 5.3086) (xy -15.9004 -4.318) (xy 19.9136 -4.318)
				(xy 19.9136 5.3086) (xy 15.0114 5.3086) (xy 15.0114 15.494)
			)
			(stroke
				(width 0)
				(type default)
			)
			(fill no)
			(layer "F.Fab")
		)
		(fp_text user "Slit"
			(at 1.9304 5.088636 270)
			(unlocked yes)
			(layer "F.SilkS")
			(effects
				(font
					(size 1.016 1.016)
					(thickness 0.1524)
				)
				(justify left)
			)
		)
		(pad "" np_thru_hole circle
			(at -12.300204 0 270)
			(size 0.254 0.254)
			(drill 2.3114)
			(layers "*.Cu" "*.Mask")
			(clearance 1.3843)
			(thermal_gap 1.3843)
		)
		(pad "" np_thru_hole circle
			(at 16.299942 0 270)
			(size 0.254 0.254)
			(drill 2.3114)
			(layers "*.Cu" "*.Mask")
			(clearance 1.3843)
			(thermal_gap 1.3843)
		)
		(pad "A1" smd rect
			(at 11.500104 -0.309118 270)
			(size 0.7112 3.6068)
			(drill
				(offset 0 -0.381)
			)
			(layers "F.Cu" "F.Mask" "F.Paste")
			(net "PRSNT_B")
		)
		(pad "A2" smd rect
			(at 10.500106 -0.309118 270)
			(size 0.7112 3.6068)
			(drill
				(offset 0 -0.381)
			)
			(layers "F.Cu" "F.Mask" "F.Paste")
			(net "P12V")
		)
		(pad "A3" smd rect
			(at 9.500108 -0.309118 270)
			(size 0.7112 3.6068)
			(drill
				(offset 0 -0.381)
			)
			(layers "F.Cu" "F.Mask" "F.Paste")
			(net "P12V")
		)
		(pad "A4" smd rect
			(at 8.50011 -0.309118 270)
			(size 0.7112 3.6068)
			(drill
				(offset 0 -0.381)
			)
			(layers "F.Cu" "F.Mask" "F.Paste")
			(net "P12V")
		)
		(pad "A5" smd rect
			(at 7.500112 -0.309118 270)
			(size 0.7112 3.6068)
			(drill
				(offset 0 -0.381)
			)
			(layers "F.Cu" "F.Mask" "F.Paste")
			(net "P12V")
		)
		(pad "A6" smd rect
			(at 6.500114 -0.309118 270)
			(size 0.7112 3.6068)
			(drill
				(offset 0 -0.381)
			)
			(layers "F.Cu" "F.Mask" "F.Paste")
			(net "P12V")
		)
		(pad "A7" smd rect
			(at 5.500116 -0.309118 270)
			(size 0.7112 3.6068)
			(drill
				(offset 0 -0.381)
			)
			(layers "F.Cu" "F.Mask" "F.Paste")
			(net "P12V")
		)
		(pad "A8" smd rect
			(at 4.500118 -0.309118 270)
			(size 0.7112 3.6068)
			(drill
				(offset 0 -0.381)
			)
			(layers "F.Cu" "F.Mask" "F.Paste")
			(net "P12V")
		)
		(pad "A9" smd rect
			(at 3.50012 -0.309118 270)
			(size 0.7112 3.6068)
			(drill
				(offset 0 -0.381)
			)
			(layers "F.Cu" "F.Mask" "F.Paste")
			(net "Net_87")
		)
		(pad "A10" smd rect
			(at 2.500122 -0.309118 270)
			(size 0.7112 3.6068)
			(drill
				(offset 0 -0.381)
			)
			(layers "F.Cu" "F.Mask" "F.Paste")
			(net "Net_86")
		)
		(pad "A11" smd rect
			(at 1.500124 -0.309118 270)
			(size 0.7112 3.6068)
			(drill
				(offset 0 -0.381)
			)
			(layers "F.Cu" "F.Mask" "F.Paste")
			(net "Net_85")
		)
		(pad "A12" smd rect
			(at -1.500124 -0.309118 270)
			(size 0.7112 3.6068)
			(drill
				(offset 0 -0.381)
			)
			(layers "F.Cu" "F.Mask" "F.Paste")
			(net "Net_94")
		)
		(pad "A13" smd rect
			(at -2.500122 -0.309118 270)
			(size 0.7112 3.6068)
			(drill
				(offset 0 -0.381)
			)
			(layers "F.Cu" "F.Mask" "F.Paste")
			(net "GND")
		)
		(pad "A14" smd rect
			(at -3.50012 -0.309118 270)
			(size 0.7112 3.6068)
			(drill
				(offset 0 -0.381)
			)
			(layers "F.Cu" "F.Mask" "F.Paste")
			(net "Net_93")
		)
		(pad "A15" smd rect
			(at -4.500118 -0.309118 270)
			(size 0.7112 3.6068)
			(drill
				(offset 0 -0.381)
			)
			(layers "F.Cu" "F.Mask" "F.Paste")
			(net "Net_92")
		)
		(pad "A16" smd rect
			(at -5.500116 -0.309118 270)
			(size 0.7112 3.6068)
			(drill
				(offset 0 -0.381)
			)
			(layers "F.Cu" "F.Mask" "F.Paste")
			(net "GND")
		)
		(pad "A17" smd rect
			(at -6.500114 -0.309118 270)
			(size 0.7112 3.6068)
			(drill
				(offset 0 -0.381)
			)
			(layers "F.Cu" "F.Mask" "F.Paste")
			(net "Net_97")
		)
		(pad "A18" smd rect
			(at -7.500112 -0.309118 270)
			(size 0.7112 3.6068)
			(drill
				(offset 0 -0.381)
			)
			(layers "F.Cu" "F.Mask" "F.Paste")
			(net "GND")
		)
		(pad "B1" smd rect
			(at 11.500104 -0.690118 270)
			(size 0.7112 3.6068)
			(layers "F.Cu" "F.Mask" "F.Paste")
			(net "GND")
		)
		(pad "B2" smd rect
			(at 10.500106 -0.690118 270)
			(size 0.7112 3.6068)
			(layers "F.Cu" "F.Mask" "F.Paste")
			(net "GND")
		)
		(pad "B3" smd rect
			(at 9.500108 -0.690118 270)
			(size 0.7112 3.6068)
			(layers "F.Cu" "F.Mask" "F.Paste")
			(net "GND")
		)
		(pad "B4" smd rect
			(at 8.50011 -0.690118 270)
			(size 0.7112 3.6068)
			(layers "F.Cu" "F.Mask" "F.Paste")
			(net "GND")
		)
		(pad "B5" smd rect
			(at 7.500112 -0.690118 270)
			(size 0.7112 3.6068)
			(layers "F.Cu" "F.Mask" "F.Paste")
			(net "GND")
		)
		(pad "B6" smd rect
			(at 6.500114 -0.690118 270)
			(size 0.7112 3.6068)
			(layers "F.Cu" "F.Mask" "F.Paste")
			(net "GND")
		)
		(pad "B7" smd rect
			(at 5.500116 -0.690118 270)
			(size 0.7112 3.6068)
			(layers "F.Cu" "F.Mask" "F.Paste")
			(net "GND")
		)
		(pad "B8" smd rect
			(at 4.500118 -0.690118 270)
			(size 0.7112 3.6068)
			(layers "F.Cu" "F.Mask" "F.Paste")
			(net "Net_91")
		)
		(pad "B9" smd rect
			(at 3.50012 -0.690118 270)
			(size 0.7112 3.6068)
			(layers "F.Cu" "F.Mask" "F.Paste")
			(net "Net_90")
		)
		(pad "B10" smd rect
			(at 2.500122 -0.690118 270)
			(size 0.7112 3.6068)
			(layers "F.Cu" "F.Mask" "F.Paste")
			(net "Net_89")
		)
		(pad "B11" smd rect
			(at 1.500124 -0.690118 270)
			(size 0.7112 3.6068)
			(layers "F.Cu" "F.Mask" "F.Paste")
			(net "Net_88")
		)
		(pad "B12" smd rect
			(at -1.500124 -0.690118 270)
			(size 0.7112 3.6068)
			(layers "F.Cu" "F.Mask" "F.Paste")
			(net "GND")
		)
		(pad "B13" smd rect
			(at -2.500122 -0.690118 270)
			(size 0.7112 3.6068)
			(layers "F.Cu" "F.Mask" "F.Paste")
			(net "Net_96")
		)
		(pad "B14" smd rect
			(at -3.50012 -0.690118 270)
			(size 0.7112 3.6068)
			(layers "F.Cu" "F.Mask" "F.Paste")
			(net "Net_95")
		)
		(pad "B15" smd rect
			(at -4.500118 -0.690118 270)
			(size 0.7112 3.6068)
			(layers "F.Cu" "F.Mask" "F.Paste")
			(net "GND")
		)
		(pad "B16" smd rect
			(at -5.500116 -0.690118 270)
			(size 0.7112 3.6068)
			(layers "F.Cu" "F.Mask" "F.Paste")
			(net "Net_99")
		)
		(pad "B17" smd rect
			(at -6.500114 -0.690118 270)
			(size 0.7112 3.6068)
			(layers "F.Cu" "F.Mask" "F.Paste")
			(net "Net_98")
		)
		(pad "B18" smd rect
			(at -7.500112 -0.690118 270)
			(size 0.7112 3.6068)
			(layers "F.Cu" "F.Mask" "F.Paste")
			(net "GND")
		)
		(zone
			(layers "F.Cu" "B.Cu" "In1.Cu" "In2.Cu" "In3.Cu" "In4.Cu" "In5.Cu" "In6.Cu")
			(hatch none 0.5)
			(connect_pads
				(clearance 0)
			)
			(min_thickness 0.25)
			(keepout
				(tracks not_allowed)
				(vias allowed)
				(pads allowed)
				(copperpour not_allowed)
				(footprints allowed)
			)
			(placement
				(enabled no)
				(sheetname "")
			)
			(fill
				(thermal_gap 0.5)
				(thermal_bridge_width 0.5)
				(island_removal_mode 0)
			)
			(polygon
				(pts
					(arc
						(start 3.960622 -67.504818)
						(mid 1.039622 -67.504818)
						(end 3.960622 -67.504818)
					)
				)
			)
		)
		(zone
			(layers "F.Cu" "B.Cu" "In1.Cu" "In2.Cu" "In3.Cu" "In4.Cu" "In5.Cu" "In6.Cu")
			(hatch none 0.5)
			(connect_pads
				(clearance 0)
			)
			(min_thickness 0.25)
			(keepout
				(tracks not_allowed)
				(vias allowed)
				(pads allowed)
				(copperpour not_allowed)
				(footprints allowed)
			)
			(placement
				(enabled no)
				(sheetname "")
			)
			(fill
				(thermal_gap 0.5)
				(thermal_bridge_width 0.5)
				(island_removal_mode 0)
			)
			(polygon
				(pts
					(arc
						(start 3.960622 -38.904672)
						(mid 1.039622 -38.904672)
						(end 3.960622 -38.904672)
					)
				)
			)
		)
	)
	(footprint ""
		(layer "F.Cu")
		(at 67.182746 -180.0987 -90)
		(property "Reference" "Q17"
			(at 0 0 270)
			(layer "F.SilkS")
			(hide yes)
			(effects
				(font
					(size 1.27 1.27)
				)
			)
		)
		(property "Value" "AO4406AL-GP"
			(at -3.707384 -1.5367 270)
			(unlocked yes)
			(layer "F.Fab")
			(hide yes)
			(effects
				(font
					(size 1.016 1.016)
					(thickness 0.1524)
				)
			)
		)
		(property "Device Type" "SOIC8H69"
			(at -3.707384 -3.0607 270)
			(unlocked yes)
			(layer "F.Fab")
			(hide yes)
			(effects
				(font
					(size 1.016 1.016)
					(thickness 0.1524)
				)
			)
		)
		(duplicate_pad_numbers_are_jumpers no)
		(fp_line
			(start -2.6289 3.4417)
			(end -2.6289 1.4732)
			(stroke
				(width 0.381)
				(type default)
			)
			(layer "F.SilkS")
		)
		(fp_line
			(start -2.7432 1.4224)
			(end -2.6416 1.4224)
			(stroke
				(width 0.1524)
				(type default)
			)
			(layer "F.SilkS")
		)
		(fp_line
			(start -2.7432 1.4224)
			(end 2.1336 1.4224)
			(stroke
				(width 0.1524)
				(type default)
			)
			(layer "F.SilkS")
		)
		(fp_line
			(start 2.1336 1.4224)
			(end 2.1336 -1.4224)
			(stroke
				(width 0.1524)
				(type default)
			)
			(layer "F.SilkS")
		)
		(fp_line
			(start -2.1844 -0.0508)
			(end -2.7178 0.508)
			(stroke
				(width 0.1524)
				(type default)
			)
			(layer "F.SilkS")
		)
		(fp_line
			(start -2.7178 -0.508)
			(end -2.1844 -0.0508)
			(stroke
				(width 0.1524)
				(type default)
			)
			(layer "F.SilkS")
		)
		(fp_line
			(start -2.7432 -1.4224)
			(end -2.7432 1.4224)
			(stroke
				(width 0.1524)
				(type default)
			)
			(layer "F.SilkS")
		)
		(fp_line
			(start 2.1336 -1.4224)
			(end -2.7432 -1.4224)
			(stroke
				(width 0.1524)
				(type default)
			)
			(layer "F.SilkS")
		)
		(fp_poly
			(pts
				(xy -2.2098 -1.4224) (xy -2.2098 1.4224) (xy 2.2098 1.4224) (xy 2.2098 -1.4224)
			)
			(stroke
				(width 0)
				(type default)
			)
			(fill yes)
			(layer "F.SilkS")
		)
		(fp_rect
			(start -2.450084 2.999994)
			(end 2.450084 -2.999994)
			(stroke
				(width 0)
				(type default)
			)
			(fill no)
			(layer "F.CrtYd")
		)
		(fp_poly
			(pts
				(xy -2.8194 3.6322) (xy -2.8194 -3.6322) (xy 2.8194 -3.6322) (xy 2.8194 1.18364) (xy 2.450084 1.18364)
				(xy 2.450084 -2.999994) (xy -2.450084 -2.999994) (xy -2.450084 2.999994) (xy 2.450084 2.999994)
				(xy 2.450084 1.18618) (xy 2.8194 1.18618) (xy 2.8194 3.6322)
			)
			(stroke
				(width 0)
				(type default)
			)
			(fill no)
			(layer "F.CrtYd")
		)
		(fp_rect
			(start -2.8194 3.6322)
			(end 2.8194 -3.6322)
			(stroke
				(width 0)
				(type default)
			)
			(fill no)
			(layer "F.Fab")
		)
		(pad "1" smd rect
			(at -1.905 2.54 270)
			(size 0.635 1.651)
			(layers "F.Cu" "F.Mask" "F.Paste")
			(net "P5V_HDD8")
		)
		(pad "2" smd rect
			(at -0.635 2.54 270)
			(size 0.635 1.651)
			(layers "F.Cu" "F.Mask" "F.Paste")
			(net "P5V_HDD8")
		)
		(pad "3" smd rect
			(at 0.635 2.54 270)
			(size 0.635 1.651)
			(layers "F.Cu" "F.Mask" "F.Paste")
			(net "P5V_HDD8")
		)
		(pad "4" smd rect
			(at 1.905 2.54 270)
			(size 0.635 1.651)
			(layers "F.Cu" "F.Mask" "F.Paste")
			(net "SW_HDD8_P")
		)
		(pad "5" smd rect
			(at 1.905 -2.54 270)
			(size 0.635 1.651)
			(layers "F.Cu" "F.Mask" "F.Paste")
			(net "P5VB")
		)
		(pad "6" smd rect
			(at 0.635 -2.54 270)
			(size 0.635 1.651)
			(layers "F.Cu" "F.Mask" "F.Paste")
			(net "P5VB")
		)
		(pad "7" smd rect
			(at -0.635 -2.54 270)
			(size 0.635 1.651)
			(layers "F.Cu" "F.Mask" "F.Paste")
			(net "P5VB")
		)
		(pad "8" smd rect
			(at -1.905 -2.54 270)
			(size 0.635 1.651)
			(layers "F.Cu" "F.Mask" "F.Paste")
			(net "P5VB")
		)
	)
)
